(kicad_pcb
	(version 20260206)
	(generator "pcbnew")
	(generator_version "10.0")
	(general
		(thickness 1.6)
		(legacy_teardrops no)
	)
	(paper "A4")
	(title_block
		(title "01162023_DA0F0TEBIF0_F0T_Expander_BD_F_brd_V02_OCP.brd")
		(comment 1 "Grand Teton / footprints 4357-4363 of 9728")
	)
	(layers
		(0 "F.Cu" signal "TOP")
		(4 "In1.Cu" signal "GND")
		(6 "In2.Cu" signal "VCC")
		(8 "In3.Cu" signal "VCC1")
		(10 "In4.Cu" signal "GND1")
		(12 "In5.Cu" signal "IN1")
		(14 "In6.Cu" signal "GND2")
		(16 "In7.Cu" signal "IN2")
		(18 "In8.Cu" signal "GND3")
		(20 "In9.Cu" signal "IN3")
		(22 "In10.Cu" signal "GND4")
		(24 "In11.Cu" signal "IN4")
		(26 "In12.Cu" signal "GND5")
		(28 "In13.Cu" signal "IN5")
		(30 "In14.Cu" signal "GND6")
		(32 "In15.Cu" signal "IN6")
		(34 "In16.Cu" signal "GND7")
		(2 "B.Cu" signal "BOTTOM")
		(9 "F.Adhes" user "F.Adhesive")
		(11 "B.Adhes" user "B.Adhesive")
		(13 "F.Paste" user "Package Geometry/Pastemask Top")
		(15 "B.Paste" user "Package Geometry/Pastemask Bottom")
		(5 "F.SilkS" user "Ref Des/Silkscreen Top")
		(7 "B.SilkS" user "Ref Des/Silkscreen Bottom")
		(1 "F.Mask" user "Board Geometry/Soldermask Top")
		(3 "B.Mask" user "Board Geometry/Soldermask Bottom")
		(17 "Dwgs.User" user "User.Drawings")
		(19 "Cmts.User" user "User.Comments")
		(21 "Eco1.User" user "User.Eco1")
		(23 "Eco2.User" user "User.Eco2")
		(25 "Edge.Cuts" user "Board Geometry/Outline")
		(27 "Margin" user)
		(31 "F.CrtYd" user "Package Geometry/Place Bound Top")
		(29 "B.CrtYd" user "Package Geometry/Place Bound Bottom")
		(35 "F.Fab" user "Ref Des/Assembly Top")
		(33 "B.Fab" user "Ref Des/Assembly Bottom")
	)
	(footprint ""
		(layer "F.Cu")
		(at 92.828872 -239.64392 180)
		(property "Reference" "R775"
			(at 0 0 180)
			(layer "F.SilkS")
			(hide yes)
			(effects
				(font
					(size 1.27 1.27)
				)
			)
		)
		(property "Value" ""
			(at 0 0 180)
			(layer "F.Fab")
			(effects
				(font
					(size 1.27 1.27)
				)
			)
		)
		(duplicate_pad_numbers_are_jumpers no)
		(fp_line
			(start 0.7874 0.4064)
			(end -0.7874 0.4064)
			(stroke
				(width 0.1524)
				(type default)
			)
			(layer "F.SilkS")
		)
		(fp_line
			(start 0.7874 -0.4064)
			(end 0.7874 0.4064)
			(stroke
				(width 0.1524)
				(type default)
			)
			(layer "F.SilkS")
		)
		(fp_line
			(start -0.7874 0.4064)
			(end -0.7874 -0.4064)
			(stroke
				(width 0.1524)
				(type default)
			)
			(layer "F.SilkS")
		)
		(fp_line
			(start -0.7874 -0.4064)
			(end 0.7874 -0.4064)
			(stroke
				(width 0.1524)
				(type default)
			)
			(layer "F.SilkS")
		)
		(fp_line
			(start 0.67945 0.3048)
			(end 0.120396 0.3048)
			(stroke
				(width 0.1)
				(type default)
			)
			(layer "F.Fab")
		)
		(fp_line
			(start 0.67945 -0.3048)
			(end 0.67945 0.3048)
			(stroke
				(width 0.1)
				(type default)
			)
			(layer "F.Fab")
		)
		(fp_line
			(start 0.12065 -0.2794)
			(end 0.12065 -0.3048)
			(stroke
				(width 0.1)
				(type default)
			)
			(layer "F.Fab")
		)
		(fp_line
			(start 0.12065 -0.3048)
			(end 0.67945 -0.3048)
			(stroke
				(width 0.1)
				(type default)
			)
			(layer "F.Fab")
		)
		(fp_line
			(start 0.120396 0.3048)
			(end 0.120396 0.2794)
			(stroke
				(width 0.1)
				(type default)
			)
			(layer "F.Fab")
		)
		(fp_line
			(start 0.120396 0.2794)
			(end -0.12065 0.2794)
			(stroke
				(width 0.1)
				(type default)
			)
			(layer "F.Fab")
		)
		(fp_line
			(start -0.12065 0.3048)
			(end -0.67945 0.3048)
			(stroke
				(width 0.1)
				(type default)
			)
			(layer "F.Fab")
		)
		(fp_line
			(start -0.12065 0.2794)
			(end -0.12065 0.3048)
			(stroke
				(width 0.1)
				(type default)
			)
			(layer "F.Fab")
		)
		(fp_line
			(start -0.12065 -0.2794)
			(end 0.12065 -0.2794)
			(stroke
				(width 0.1)
				(type default)
			)
			(layer "F.Fab")
		)
		(fp_line
			(start -0.12065 -0.305054)
			(end -0.12065 -0.2794)
			(stroke
				(width 0.1)
				(type default)
			)
			(layer "F.Fab")
		)
		(fp_line
			(start -0.67945 0.3048)
			(end -0.67945 -0.305054)
			(stroke
				(width 0.1)
				(type default)
			)
			(layer "F.Fab")
		)
		(fp_line
			(start -0.67945 -0.305054)
			(end -0.12065 -0.305054)
			(stroke
				(width 0.1)
				(type default)
			)
			(layer "F.Fab")
		)
		(pad "1" smd circle
			(at -0.40005 0 180)
			(size 0 0)
			(layers "F.Cu" "F.Mask" "F.Paste")
			(net "SMB_BIC_I2C6_MUX_PEX_ADC_R_SCL")
		)
		(pad "2" smd circle
			(at 0.40005 0 180)
			(size 0 0)
			(layers "F.Cu" "F.Mask" "F.Paste")
			(net "SMB_PEX0_P1V25_ADC_SCL")
		)
	)
	(footprint ""
		(layer "F.Cu")
		(at 261.74192 -305.648106 -135)
		(property "Reference" "R1375"
			(at 0 0 225)
			(layer "F.SilkS")
			(hide yes)
			(effects
				(font
					(size 1.27 1.27)
				)
			)
		)
		(property "Value" ""
			(at 0 0 225)
			(layer "F.Fab")
			(effects
				(font
					(size 1.27 1.27)
				)
			)
		)
		(duplicate_pad_numbers_are_jumpers no)
		(fp_line
			(start 0.787389 0.406267)
			(end -0.787389 0.406267)
			(stroke
				(width 0.1524)
				(type default)
			)
			(layer "F.SilkS")
		)
		(fp_line
			(start 0.787389 -0.406267)
			(end 0.787389 0.406267)
			(stroke
				(width 0.1524)
				(type default)
			)
			(layer "F.SilkS")
		)
		(fp_line
			(start -0.787389 0.406267)
			(end -0.787389 -0.406267)
			(stroke
				(width 0.1524)
				(type default)
			)
			(layer "F.SilkS")
		)
		(fp_line
			(start -0.787389 -0.406267)
			(end 0.787389 -0.406267)
			(stroke
				(width 0.1524)
				(type default)
			)
			(layer "F.SilkS")
		)
		(fp_line
			(start 0.679446 0.30479)
			(end 0.120515 0.30479)
			(stroke
				(width 0.1)
				(type default)
			)
			(layer "F.Fab")
		)
		(fp_line
			(start 0.120515 0.30479)
			(end 0.120335 0.279466)
			(stroke
				(width 0.1)
				(type default)
			)
			(layer "F.Fab")
		)
		(fp_line
			(start 0.120335 0.279466)
			(end -0.120695 0.279466)
			(stroke
				(width 0.1)
				(type default)
			)
			(layer "F.Fab")
		)
		(fp_line
			(start 0.679446 -0.30479)
			(end 0.679446 0.30479)
			(stroke
				(width 0.1)
				(type default)
			)
			(layer "F.Fab")
		)
		(fp_line
			(start -0.120515 0.30479)
			(end -0.679446 0.30479)
			(stroke
				(width 0.1)
				(type default)
			)
			(layer "F.Fab")
		)
		(fp_line
			(start -0.120695 0.279466)
			(end -0.120515 0.30479)
			(stroke
				(width 0.1)
				(type default)
			)
			(layer "F.Fab")
		)
		(fp_line
			(start 0.120695 -0.279466)
			(end 0.120515 -0.30479)
			(stroke
				(width 0.1)
				(type default)
			)
			(layer "F.Fab")
		)
		(fp_line
			(start 0.120515 -0.30479)
			(end 0.679446 -0.30479)
			(stroke
				(width 0.1)
				(type default)
			)
			(layer "F.Fab")
		)
		(fp_line
			(start -0.679446 0.30479)
			(end -0.679446 -0.305149)
			(stroke
				(width 0.1)
				(type default)
			)
			(layer "F.Fab")
		)
		(fp_line
			(start -0.120695 -0.279466)
			(end 0.120695 -0.279466)
			(stroke
				(width 0.1)
				(type default)
			)
			(layer "F.Fab")
		)
		(fp_line
			(start -0.120695 -0.304969)
			(end -0.120695 -0.279466)
			(stroke
				(width 0.1)
				(type default)
			)
			(layer "F.Fab")
		)
		(fp_line
			(start -0.679446 -0.305149)
			(end -0.120695 -0.304969)
			(stroke
				(width 0.1)
				(type default)
			)
			(layer "F.Fab")
		)
		(pad "1" smd circle
			(at -0.40005 0 225)
			(size 0 0)
			(layers "F.Cu" "F.Mask" "F.Paste")
			(net "PEX2_DFT_IDDT")
		)
		(pad "2" smd circle
			(at 0.40005 0 225)
			(size 0 0)
			(layers "F.Cu" "F.Mask" "F.Paste")
			(net "P1V8_PEX")
		)
	)
	(footprint ""
		(layer "F.Cu")
		(at 116.27739 -254.55372 180)
		(property "Reference" "PC47"
			(at 0 0 180)
			(layer "F.SilkS")
			(hide yes)
			(effects
				(font
					(size 1.27 1.27)
				)
			)
		)
		(property "Value" ""
			(at 0 0 180)
			(layer "F.Fab")
			(effects
				(font
					(size 1.27 1.27)
				)
			)
		)
		(duplicate_pad_numbers_are_jumpers no)
		(fp_line
			(start 0.7874 0.4064)
			(end -0.7874 0.4064)
			(stroke
				(width 0.1524)
				(type default)
			)
			(layer "F.SilkS")
		)
		(fp_line
			(start 0.7874 -0.4064)
			(end 0.7874 0.4064)
			(stroke
				(width 0.1524)
				(type default)
			)
			(layer "F.SilkS")
		)
		(fp_line
			(start -0.7874 0.4064)
			(end -0.7874 -0.4064)
			(stroke
				(width 0.1524)
				(type default)
			)
			(layer "F.SilkS")
		)
		(fp_line
			(start -0.7874 -0.4064)
			(end 0.7874 -0.4064)
			(stroke
				(width 0.1524)
				(type default)
			)
			(layer "F.SilkS")
		)
		(fp_line
			(start 0.67945 0.3048)
			(end 0.120396 0.3048)
			(stroke
				(width 0.1)
				(type default)
			)
			(layer "F.Fab")
		)
		(fp_line
			(start 0.67945 -0.3048)
			(end 0.67945 0.3048)
			(stroke
				(width 0.1)
				(type default)
			)
			(layer "F.Fab")
		)
		(fp_line
			(start 0.12065 -0.2794)
			(end 0.12065 -0.3048)
			(stroke
				(width 0.1)
				(type default)
			)
			(layer "F.Fab")
		)
		(fp_line
			(start 0.12065 -0.3048)
			(end 0.67945 -0.3048)
			(stroke
				(width 0.1)
				(type default)
			)
			(layer "F.Fab")
		)
		(fp_line
			(start 0.120396 0.3048)
			(end 0.120396 0.2794)
			(stroke
				(width 0.1)
				(type default)
			)
			(layer "F.Fab")
		)
		(fp_line
			(start 0.120396 0.2794)
			(end -0.12065 0.2794)
			(stroke
				(width 0.1)
				(type default)
			)
			(layer "F.Fab")
		)
		(fp_line
			(start -0.12065 0.3048)
			(end -0.67945 0.3048)
			(stroke
				(width 0.1)
				(type default)
			)
			(layer "F.Fab")
		)
		(fp_line
			(start -0.12065 0.2794)
			(end -0.12065 0.3048)
			(stroke
				(width 0.1)
				(type default)
			)
			(layer "F.Fab")
		)
		(fp_line
			(start -0.12065 -0.2794)
			(end 0.12065 -0.2794)
			(stroke
				(width 0.1)
				(type default)
			)
			(layer "F.Fab")
		)
		(fp_line
			(start -0.12065 -0.305054)
			(end -0.12065 -0.2794)
			(stroke
				(width 0.1)
				(type default)
			)
			(layer "F.Fab")
		)
		(fp_line
			(start -0.67945 0.3048)
			(end -0.67945 -0.305054)
			(stroke
				(width 0.1)
				(type default)
			)
			(layer "F.Fab")
		)
		(fp_line
			(start -0.67945 -0.305054)
			(end -0.12065 -0.305054)
			(stroke
				(width 0.1)
				(type default)
			)
			(layer "F.Fab")
		)
		(pad "1" smd circle
			(at -0.40005 0 180)
			(size 0 0)
			(layers "F.Cu" "F.Mask" "F.Paste")
			(net "P0V8_PEX0_VREF")
		)
		(pad "2" smd circle
			(at 0.40005 0 180)
			(size 0 0)
			(layers "F.Cu" "F.Mask" "F.Paste")
			(net "GND")
		)
	)
	(footprint ""
		(layer "F.Cu")
		(at 11.2776 -273.31543 135)
		(property "Reference" "C627"
			(at 0 0 135)
			(layer "F.SilkS")
			(hide yes)
			(effects
				(font
					(size 1.27 1.27)
				)
			)
		)
		(property "Value" ""
			(at 0 0 135)
			(layer "F.Fab")
			(effects
				(font
					(size 1.27 1.27)
				)
			)
		)
		(duplicate_pad_numbers_are_jumpers no)
		(fp_line
			(start 0.787389 -0.406267)
			(end 0.787389 0.406267)
			(stroke
				(width 0.1524)
				(type default)
			)
			(layer "F.SilkS")
		)
		(fp_line
			(start 0.787389 0.406267)
			(end -0.787389 0.406267)
			(stroke
				(width 0.1524)
				(type default)
			)
			(layer "F.SilkS")
		)
		(fp_line
			(start -0.787389 -0.406267)
			(end 0.787389 -0.406267)
			(stroke
				(width 0.1524)
				(type default)
			)
			(layer "F.SilkS")
		)
		(fp_line
			(start -0.787389 0.406267)
			(end -0.787389 -0.406267)
			(stroke
				(width 0.1524)
				(type default)
			)
			(layer "F.SilkS")
		)
		(fp_line
			(start 0.679446 -0.30479)
			(end 0.679446 0.30479)
			(stroke
				(width 0.1)
				(type default)
			)
			(layer "F.Fab")
		)
		(fp_line
			(start 0.120515 -0.30479)
			(end 0.679446 -0.30479)
			(stroke
				(width 0.1)
				(type default)
			)
			(layer "F.Fab")
		)
		(fp_line
			(start 0.120695 -0.279466)
			(end 0.120515 -0.30479)
			(stroke
				(width 0.1)
				(type default)
			)
			(layer "F.Fab")
		)
		(fp_line
			(start 0.679446 0.30479)
			(end 0.120515 0.30479)
			(stroke
				(width 0.1)
				(type default)
			)
			(layer "F.Fab")
		)
		(fp_line
			(start -0.120695 -0.304969)
			(end -0.120695 -0.279466)
			(stroke
				(width 0.1)
				(type default)
			)
			(layer "F.Fab")
		)
		(fp_line
			(start -0.120695 -0.279466)
			(end 0.120695 -0.279466)
			(stroke
				(width 0.1)
				(type default)
			)
			(layer "F.Fab")
		)
		(fp_line
			(start 0.120335 0.279466)
			(end -0.120695 0.279466)
			(stroke
				(width 0.1)
				(type default)
			)
			(layer "F.Fab")
		)
		(fp_line
			(start 0.120515 0.30479)
			(end 0.120335 0.279466)
			(stroke
				(width 0.1)
				(type default)
			)
			(layer "F.Fab")
		)
		(fp_line
			(start -0.679446 -0.305149)
			(end -0.120695 -0.304969)
			(stroke
				(width 0.1)
				(type default)
			)
			(layer "F.Fab")
		)
		(fp_line
			(start -0.120695 0.279466)
			(end -0.120515 0.30479)
			(stroke
				(width 0.1)
				(type default)
			)
			(layer "F.Fab")
		)
		(fp_line
			(start -0.120515 0.30479)
			(end -0.679446 0.30479)
			(stroke
				(width 0.1)
				(type default)
			)
			(layer "F.Fab")
		)
		(fp_line
			(start -0.679446 0.30479)
			(end -0.679446 -0.305149)
			(stroke
				(width 0.1)
				(type default)
			)
			(layer "F.Fab")
		)
		(pad "1" smd circle
			(at -0.40005 0 135)
			(size 0 0)
			(layers "F.Cu" "F.Mask" "F.Paste")
			(net "P12V_PEX0_P1V25_VIN_P")
		)
		(pad "2" smd circle
			(at 0.40005 0 135)
			(size 0 0)
			(layers "F.Cu" "F.Mask" "F.Paste")
			(net "P12V_PEX0_P1V25_VIN_N")
		)
	)
	(footprint ""
		(layer "F.Cu")
		(at 196.639434 -137.645648)
		(property "Reference" "R158"
			(at 0 0 0)
			(layer "F.SilkS")
			(hide yes)
			(effects
				(font
					(size 1.27 1.27)
				)
			)
		)
		(property "Value" ""
			(at 0 0 0)
			(layer "F.Fab")
			(effects
				(font
					(size 1.27 1.27)
				)
			)
		)
		(duplicate_pad_numbers_are_jumpers no)
		(fp_line
			(start -0.7874 -0.4064)
			(end 0.7874 -0.4064)
			(stroke
				(width 0.1524)
				(type default)
			)
			(layer "F.SilkS")
		)
		(fp_line
			(start -0.7874 0.4064)
			(end -0.7874 -0.4064)
			(stroke
				(width 0.1524)
				(type default)
			)
			(layer "F.SilkS")
		)
		(fp_line
			(start 0.7874 -0.4064)
			(end 0.7874 0.4064)
			(stroke
				(width 0.1524)
				(type default)
			)
			(layer "F.SilkS")
		)
		(fp_line
			(start 0.7874 0.4064)
			(end -0.7874 0.4064)
			(stroke
				(width 0.1524)
				(type default)
			)
			(layer "F.SilkS")
		)
		(fp_line
			(start -0.67945 -0.305054)
			(end -0.12065 -0.305054)
			(stroke
				(width 0.1)
				(type default)
			)
			(layer "F.Fab")
		)
		(fp_line
			(start -0.67945 0.3048)
			(end -0.67945 -0.305054)
			(stroke
				(width 0.1)
				(type default)
			)
			(layer "F.Fab")
		)
		(fp_line
			(start -0.12065 -0.305054)
			(end -0.12065 -0.2794)
			(stroke
				(width 0.1)
				(type default)
			)
			(layer "F.Fab")
		)
		(fp_line
			(start -0.12065 -0.2794)
			(end 0.12065 -0.2794)
			(stroke
				(width 0.1)
				(type default)
			)
			(layer "F.Fab")
		)
		(fp_line
			(start -0.12065 0.2794)
			(end -0.12065 0.3048)
			(stroke
				(width 0.1)
				(type default)
			)
			(layer "F.Fab")
		)
		(fp_line
			(start -0.12065 0.3048)
			(end -0.67945 0.3048)
			(stroke
				(width 0.1)
				(type default)
			)
			(layer "F.Fab")
		)
		(fp_line
			(start 0.120396 0.2794)
			(end -0.12065 0.2794)
			(stroke
				(width 0.1)
				(type default)
			)
			(layer "F.Fab")
		)
		(fp_line
			(start 0.120396 0.3048)
			(end 0.120396 0.2794)
			(stroke
				(width 0.1)
				(type default)
			)
			(layer "F.Fab")
		)
		(fp_line
			(start 0.12065 -0.3048)
			(end 0.67945 -0.3048)
			(stroke
				(width 0.1)
				(type default)
			)
			(layer "F.Fab")
		)
		(fp_line
			(start 0.12065 -0.2794)
			(end 0.12065 -0.3048)
			(stroke
				(width 0.1)
				(type default)
			)
			(layer "F.Fab")
		)
		(fp_line
			(start 0.67945 -0.3048)
			(end 0.67945 0.3048)
			(stroke
				(width 0.1)
				(type default)
			)
			(layer "F.Fab")
		)
		(fp_line
			(start 0.67945 0.3048)
			(end 0.120396 0.3048)
			(stroke
				(width 0.1)
				(type default)
			)
			(layer "F.Fab")
		)
		(pad "1" smd circle
			(at -0.40005 0)
			(size 0 0)
			(layers "F.Cu" "F.Mask" "F.Paste")
			(net "PRSNTB0_NIC3_N")
		)
		(pad "2" smd circle
			(at 0.40005 0)
			(size 0 0)
			(layers "F.Cu" "F.Mask" "F.Paste")
			(net "P3V3_AUX")
		)
	)
	(footprint ""
		(layer "F.Cu")
		(at 166.184072 -343.952322 90)
		(property "Reference" "C2515"
			(at 0 0 90)
			(layer "F.SilkS")
			(hide yes)
			(effects
				(font
					(size 1.27 1.27)
				)
			)
		)
		(property "Value" ""
			(at 0 0 90)
			(layer "F.Fab")
			(effects
				(font
					(size 1.27 1.27)
				)
			)
		)
		(duplicate_pad_numbers_are_jumpers no)
		(fp_line
			(start 0.299974 -0.150114)
			(end 0.299974 0.150114)
			(stroke
				(width 0.1)
				(type default)
			)
			(layer "F.Fab")
		)
		(fp_line
			(start -0.299974 -0.150114)
			(end 0.299974 -0.150114)
			(stroke
				(width 0.1)
				(type default)
			)
			(layer "F.Fab")
		)
		(fp_line
			(start 0.299974 0.150114)
			(end -0.299974 0.150114)
			(stroke
				(width 0.1)
				(type default)
			)
			(layer "F.Fab")
		)
		(fp_line
			(start -0.299974 0.150114)
			(end -0.299974 -0.150114)
			(stroke
				(width 0.1)
				(type default)
			)
			(layer "F.Fab")
		)
		(pad "1" smd rect
			(at -0.2667 0 90)
			(size 0.3048 0.381)
			(layers "F.Cu" "F.Mask" "F.Paste")
			(net "P5E_PEX1_STN4_TX_DN<78>")
		)
		(pad "2" smd rect
			(at 0.2667 0 90)
			(size 0.3048 0.381)
			(layers "F.Cu" "F.Mask" "F.Paste")
			(net "P5E_PEX1_STN4_TX_C_DN<78>")
		)
	)
	(footprint ""
		(layer "F.Cu")
		(at 305.730402 -66.32194 -90)
		(property "Reference" "PC873"
			(at 0 0 270)
			(layer "F.SilkS")
			(hide yes)
			(effects
				(font
					(size 1.27 1.27)
				)
			)
		)
		(property "Value" ""
			(at 0 0 270)
			(layer "F.Fab")
			(effects
				(font
					(size 1.27 1.27)
				)
			)
		)
		(duplicate_pad_numbers_are_jumpers no)
		(fp_line
			(start -0.7874 0.4064)
			(end -0.7874 -0.4064)
			(stroke
				(width 0.1524)
				(type default)
			)
			(layer "F.SilkS")
		)
		(fp_line
			(start 0.7874 0.4064)
			(end -0.7874 0.4064)
			(stroke
				(width 0.1524)
				(type default)
			)
			(layer "F.SilkS")
		)
		(fp_line
			(start -0.7874 -0.4064)
			(end 0.7874 -0.4064)
			(stroke
				(width 0.1524)
				(type default)
			)
			(layer "F.SilkS")
		)
		(fp_line
			(start 0.7874 -0.4064)
			(end 0.7874 0.4064)
			(stroke
				(width 0.1524)
				(type default)
			)
			(layer "F.SilkS")
		)
		(fp_line
			(start -0.67945 0.3048)
			(end -0.67945 -0.305054)
			(stroke
				(width 0.1)
				(type default)
			)
			(layer "F.Fab")
		)
		(fp_line
			(start -0.12065 0.3048)
			(end -0.67945 0.3048)
			(stroke
				(width 0.1)
				(type default)
			)
			(layer "F.Fab")
		)
		(fp_line
			(start 0.120396 0.3048)
			(end 0.120396 0.2794)
			(stroke
				(width 0.1)
				(type default)
			)
			(layer "F.Fab")
		)
		(fp_line
			(start 0.67945 0.3048)
			(end 0.120396 0.3048)
			(stroke
				(width 0.1)
				(type default)
			)
			(layer "F.Fab")
		)
		(fp_line
			(start -0.12065 0.2794)
			(end -0.12065 0.3048)
			(stroke
				(width 0.1)
				(type default)
			)
			(layer "F.Fab")
		)
		(fp_line
			(start 0.120396 0.2794)
			(end -0.12065 0.2794)
			(stroke
				(width 0.1)
				(type default)
			)
			(layer "F.Fab")
		)
		(fp_line
			(start -0.12065 -0.2794)
			(end 0.12065 -0.2794)
			(stroke
				(width 0.1)
				(type default)
			)
			(layer "F.Fab")
		)
		(fp_line
			(start 0.12065 -0.2794)
			(end 0.12065 -0.3048)
			(stroke
				(width 0.1)
				(type default)
			)
			(layer "F.Fab")
		)
		(fp_line
			(start 0.12065 -0.3048)
			(end 0.67945 -0.3048)
			(stroke
				(width 0.1)
				(type default)
			)
			(layer "F.Fab")
		)
		(fp_line
			(start 0.67945 -0.3048)
			(end 0.67945 0.3048)
			(stroke
				(width 0.1)
				(type default)
			)
			(layer "F.Fab")
		)
		(fp_line
			(start -0.67945 -0.305054)
			(end -0.12065 -0.305054)
			(stroke
				(width 0.1)
				(type default)
			)
			(layer "F.Fab")
		)
		(fp_line
			(start -0.12065 -0.305054)
			(end -0.12065 -0.2794)
			(stroke
				(width 0.1)
				(type default)
			)
			(layer "F.Fab")
		)
		(pad "1" smd circle
			(at -0.40005 0 270)
			(size 0 0)
			(layers "F.Cu" "F.Mask" "F.Paste")
			(net "P12V_SSD10_CO_DV_DT")
		)
		(pad "2" smd circle
			(at 0.40005 0 270)
			(size 0 0)
			(layers "F.Cu" "F.Mask" "F.Paste")
			(net "GND")
		)
	)
)
